# T6G (Grand Teton) — schematic netlist excerpt (pin names and nets, part order shuffled) for the footprints in the layout excerpt that follows; sources: Cadence DE-HDL packaged netlist, KiCad conversion of 04192023_DAF0TMB3IC0_F0TG_MB_C_brd_V02_OCP.brd

U2  PCA9617ADP  IC  pkg TSSOP8_3XB  page 160
  VCCA  = PVDD11_S3_P0
  SCLA  = SMB_CPU0_CPU1_APML_BUF2_SCL_R1
  SDAA  = SMB_CPU0_CPU1_APML_BUF2_SDA_R1
  GND  = GND
  EN  = PU_U2_EN
  SDAB  = SMB_CPU0_CPU1_APML_BUF2_SDA
  SCLB  = SMB_CPU0_CPU1_APML_BUF2_SCL
  VCCB  = P3V3_AUX

C2343  Q_CAP  22UF 4V 20% X6S  pkg C0402  page 73 : A = PVDDCR_CPU0_P1 ; B = GND

(kicad_pcb
	(version 20260206)
	(generator "pcbnew")
	(generator_version "10.0")
	(general
		(thickness 1.6)
		(legacy_teardrops no)
	)
	(paper "A4")
	(title_block
		(title "04192023_DAF0TMB3IC0_F0TG_MB_C_brd_V02_OCP.brd")
		(comment 1 "Grand Teton / footprints 7745-7746 of 8354")
	)
	(layers
		(0 "F.Cu" signal "TOP")
		(4 "In1.Cu" signal "GND")
		(6 "In2.Cu" signal "IN1")
		(8 "In3.Cu" signal "GND1")
		(10 "In4.Cu" signal "IN2")
		(12 "In5.Cu" signal "GND2")
		(14 "In6.Cu" signal "IN3")
		(16 "In7.Cu" signal "GND3")
		(18 "In8.Cu" signal "VCC")
		(20 "In9.Cu" signal "VCC1")
		(22 "In10.Cu" signal "GND4")
		(24 "In11.Cu" signal "IN4")
		(26 "In12.Cu" signal "GND5")
		(28 "In13.Cu" signal "IN5")
		(30 "In14.Cu" signal "GND6")
		(32 "In15.Cu" signal "IN6")
		(34 "In16.Cu" signal "GND7")
		(2 "B.Cu" signal "BOTTOM")
		(9 "F.Adhes" user "F.Adhesive")
		(11 "B.Adhes" user "B.Adhesive")
		(13 "F.Paste" user "Package Geometry/Pastemask Top")
		(15 "B.Paste" user "Package Geometry/Pastemask Bottom")
		(5 "F.SilkS" user "Ref Des/Silkscreen Top")
		(7 "B.SilkS" user "Ref Des/Silkscreen Bottom")
		(1 "F.Mask" user "Board Geometry/Soldermask Top")
		(3 "B.Mask" user "Board Geometry/Soldermask Bottom")
		(17 "Dwgs.User" user "User.Drawings")
		(19 "Cmts.User" user "User.Comments")
		(21 "Eco1.User" user "User.Eco1")
		(23 "Eco2.User" user "User.Eco2")
		(25 "Edge.Cuts" user "Board Geometry/Outline")
		(27 "Margin" user)
		(31 "F.CrtYd" user "Package Geometry/Place Bound Top")
		(29 "B.CrtYd" user "Package Geometry/Place Bound Bottom")
		(35 "F.Fab" user "Ref Des/Assembly Top")
		(33 "B.Fab" user "Ref Des/Assembly Bottom")
	)
	(footprint ""
		(layer "B.Cu")
		(at 230.65105 -223.041972 -90)
		(property "Reference" "U2"
			(at 0.982218 2.852674 270)
			(unlocked yes)
			(layer "B.SilkS")
			(effects
				(font
					(size 0.7874 0.5842)
					(thickness 0.1524)
				)
				(justify left mirror)
			)
		)
		(property "Value" ""
			(at 0 0 90)
			(layer "B.Fab")
			(effects
				(font
					(size 1.27 1.27)
				)
				(justify mirror)
			)
		)
		(duplicate_pad_numbers_are_jumpers no)
		(fp_line
			(start -1.463548 1.549908)
			(end 1.463548 1.549908)
			(stroke
				(width 0.1524)
				(type default)
			)
			(layer "B.SilkS")
		)
		(fp_line
			(start 1.463548 1.549908)
			(end 1.463548 -1.549908)
			(stroke
				(width 0.1524)
				(type default)
			)
			(layer "B.SilkS")
		)
		(fp_line
			(start 0 -0.762)
			(end -0.762 -1.549908)
			(stroke
				(width 0.1524)
				(type default)
			)
			(layer "B.SilkS")
		)
		(fp_line
			(start -1.463548 -1.549908)
			(end -1.463548 1.549908)
			(stroke
				(width 0.1524)
				(type default)
			)
			(layer "B.SilkS")
		)
		(fp_line
			(start -0.762 -1.549908)
			(end -1.463548 -1.549908)
			(stroke
				(width 0.1524)
				(type default)
			)
			(layer "B.SilkS")
		)
		(fp_line
			(start 0.787908 -1.549908)
			(end 0 -0.762)
			(stroke
				(width 0.1524)
				(type default)
			)
			(layer "B.SilkS")
		)
		(fp_line
			(start 1.463548 -1.549908)
			(end 0.787908 -1.549908)
			(stroke
				(width 0.1524)
				(type default)
			)
			(layer "B.SilkS")
		)
		(fp_poly
			(pts
				(xy 3.780282 -1.017524) (xy 3.160522 -1.327404) (xy 3.780282 -1.637284)
			)
			(stroke
				(width 0)
				(type default)
			)
			(fill yes)
			(layer "B.SilkS")
		)
		(fp_line
			(start -1.549908 1.549908)
			(end 1.549908 1.549908)
			(stroke
				(width 0.1)
				(type default)
			)
			(layer "B.Fab")
		)
		(fp_line
			(start 1.549908 1.549908)
			(end 1.549908 -1.549908)
			(stroke
				(width 0.1)
				(type default)
			)
			(layer "B.Fab")
		)
		(fp_line
			(start -1.549908 -1.549908)
			(end -1.549908 1.549908)
			(stroke
				(width 0.1)
				(type default)
			)
			(layer "B.Fab")
		)
		(fp_line
			(start 1.549908 -1.549908)
			(end -1.549908 -1.549908)
			(stroke
				(width 0.1)
				(type default)
			)
			(layer "B.Fab")
		)
		(fp_poly
			(pts
				(xy 3.4798 -1.359916) (xy 2.86004 -1.050036) (xy 3.4798 -0.740156)
			)
			(stroke
				(width 0)
				(type default)
			)
			(fill yes)
			(layer "B.Fab")
		)
		(pad "1" smd rect
			(at 2.175002 -1.050036)
			(size 0.6096 1.1684)
			(layers "B.Cu" "B.Mask" "B.Paste")
			(net "PVDD11_S3_P0")
		)
		(pad "2" smd rect
			(at 2.175002 -0.32512)
			(size 0.4318 1.1684)
			(layers "B.Cu" "B.Mask" "B.Paste")
			(net "SMB_CPU0_CPU1_APML_BUF2_SCL_R1")
		)
		(pad "3" smd rect
			(at 2.175002 0.32512)
			(size 0.4318 1.1684)
			(layers "B.Cu" "B.Mask" "B.Paste")
			(net "SMB_CPU0_CPU1_APML_BUF2_SDA_R1")
		)
		(pad "4" smd rect
			(at 2.175002 1.050036)
			(size 0.6096 1.1684)
			(layers "B.Cu" "B.Mask" "B.Paste")
			(net "GND")
		)
		(pad "5" smd rect
			(at -2.175002 1.050036)
			(size 0.6096 1.1684)
			(layers "B.Cu" "B.Mask" "B.Paste")
			(net "PU_U2_EN")
		)
		(pad "6" smd rect
			(at -2.175002 0.32512)
			(size 0.4318 1.1684)
			(layers "B.Cu" "B.Mask" "B.Paste")
			(net "SMB_CPU0_CPU1_APML_BUF2_SDA")
		)
		(pad "7" smd rect
			(at -2.175002 -0.32512)
			(size 0.4318 1.1684)
			(layers "B.Cu" "B.Mask" "B.Paste")
			(net "SMB_CPU0_CPU1_APML_BUF2_SCL")
		)
		(pad "8" smd rect
			(at -2.175002 -1.050036)
			(size 0.6096 1.1684)
			(layers "B.Cu" "B.Mask" "B.Paste")
			(net "P3V3_AUX")
		)
	)
	(footprint ""
		(layer "B.Cu")
		(at 102.811834 -249.368564 180)
		(property "Reference" "C2343"
			(at 0 0 0)
			(layer "B.SilkS")
			(hide yes)
			(effects
				(font
					(size 1.27 1.27)
				)
				(justify mirror)
			)
		)
		(property "Value" ""
			(at 0 0 0)
			(layer "B.Fab")
			(effects
				(font
					(size 1.27 1.27)
				)
				(justify mirror)
			)
		)
		(duplicate_pad_numbers_are_jumpers no)
		(fp_line
			(start 0.7874 0.4064)
			(end 0.7874 -0.4064)
			(stroke
				(width 0.1524)
				(type default)
			)
			(layer "B.SilkS")
		)
		(fp_line
			(start 0.7874 -0.4064)
			(end -0.7874 -0.4064)
			(stroke
				(width 0.1524)
				(type default)
			)
			(layer "B.SilkS")
		)
		(fp_line
			(start -0.7874 0.4064)
			(end 0.7874 0.4064)
			(stroke
				(width 0.1524)
				(type default)
			)
			(layer "B.SilkS")
		)
		(fp_line
			(start -0.7874 -0.4064)
			(end -0.7874 0.4064)
			(stroke
				(width 0.1524)
				(type default)
			)
			(layer "B.SilkS")
		)
		(fp_line
			(start 0.67945 0.3048)
			(end 0.67945 -0.305054)
			(stroke
				(width 0.1)
				(type default)
			)
			(layer "B.Fab")
		)
		(fp_line
			(start 0.67945 -0.305054)
			(end 0.12065 -0.305054)
			(stroke
				(width 0.1)
				(type default)
			)
			(layer "B.Fab")
		)
		(fp_line
			(start 0.12065 0.3048)
			(end 0.67945 0.3048)
			(stroke
				(width 0.1)
				(type default)
			)
			(layer "B.Fab")
		)
		(fp_line
			(start 0.12065 0.2794)
			(end 0.12065 0.3048)
			(stroke
				(width 0.1)
				(type default)
			)
			(layer "B.Fab")
		)
		(fp_line
			(start 0.12065 -0.2794)
			(end -0.12065 -0.2794)
			(stroke
				(width 0.1)
				(type default)
			)
			(layer "B.Fab")
		)
		(fp_line
			(start 0.12065 -0.305054)
			(end 0.12065 -0.2794)
			(stroke
				(width 0.1)
				(type default)
			)
			(layer "B.Fab")
		)
		(fp_line
			(start -0.120396 0.3048)
			(end -0.120396 0.2794)
			(stroke
				(width 0.1)
				(type default)
			)
			(layer "B.Fab")
		)
		(fp_line
			(start -0.120396 0.2794)
			(end 0.12065 0.2794)
			(stroke
				(width 0.1)
				(type default)
			)
			(layer "B.Fab")
		)
		(fp_line
			(start -0.12065 -0.2794)
			(end -0.12065 -0.3048)
			(stroke
				(width 0.1)
				(type default)
			)
			(layer "B.Fab")
		)
		(fp_line
			(start -0.12065 -0.3048)
			(end -0.67945 -0.3048)
			(stroke
				(width 0.1)
				(type default)
			)
			(layer "B.Fab")
		)
		(fp_line
			(start -0.67945 0.3048)
			(end -0.120396 0.3048)
			(stroke
				(width 0.1)
				(type default)
			)
			(layer "B.Fab")
		)
		(fp_line
			(start -0.67945 -0.3048)
			(end -0.67945 0.3048)
			(stroke
				(width 0.1)
				(type default)
			)
			(layer "B.Fab")
		)
		(pad "1" smd circle
			(at 0.40005 0)
			(size 0 0)
			(layers "B.Cu" "B.Mask" "B.Paste")
			(net "PVDDCR_CPU0_P1")
		)
		(pad "2" smd circle
			(at -0.40005 0)
			(size 0 0)
			(layers "B.Cu" "B.Mask" "B.Paste")
			(net "GND")
		)
	)
)
